# BASEBOARD_FAB2 (Tioga Pass) — schematic netlist excerpt (pin names and nets, part order shuffled) for the footprints in the layout excerpt that follows; sources: Cadence DE-HDL packaged netlist, KiCad conversion of Wiwynn_Tioga_Pass_MB.brd

C1W15  CAP  10UF 6.3V 20% X6S  pkg 0603  page 239 : A = P2V5_AUX_BMC ; B = GND
C5A12  CAP_A  47UF 4V 20% X5R  pkg 0603V  page 220 : A = PVDDQ_DEF ; B = GND
R25W34  120R2F-GP  1%  pkg RCL_GP  page 151 : \1\ = BMC_M_WE_N ; \2\ = P1V2_AUX_BMC

(kicad_pcb
	(version 20260206)
	(generator "pcbnew")
	(generator_version "10.0")
	(general
		(thickness 1.6)
		(legacy_teardrops no)
	)
	(paper "A4")
	(title_block
		(title "Wiwynn_Tioga_Pass_MB.brd")
		(comment 1 "Tioga Pass / footprints 1561-1563 of 4770")
	)
	(layers
		(0 "F.Cu" signal "TOP")
		(4 "In1.Cu" signal "L2GND")
		(6 "In2.Cu" signal "L3")
		(8 "In3.Cu" signal "L4GND")
		(10 "In4.Cu" signal "L5")
		(12 "In5.Cu" signal "L6GND")
		(14 "In6.Cu" signal "L7VCC")
		(16 "In7.Cu" signal "L8VCC")
		(18 "In8.Cu" signal "L9GND")
		(20 "In9.Cu" signal "L10")
		(22 "In10.Cu" signal "L11GND")
		(24 "In11.Cu" signal "L12")
		(26 "In12.Cu" signal "L13GND")
		(2 "B.Cu" signal "BOTTOM")
		(9 "F.Adhes" user "F.Adhesive")
		(11 "B.Adhes" user "B.Adhesive")
		(13 "F.Paste" user "Package Geometry/Pastemask Top")
		(15 "B.Paste" user "Package Geometry/Pastemask Bottom")
		(5 "F.SilkS" user "Ref Des/Silkscreen Top")
		(7 "B.SilkS" user "Ref Des/Silkscreen Bottom")
		(1 "F.Mask" user "Board Geometry/Soldermask Top")
		(3 "B.Mask" user "Board Geometry/Soldermask Bottom")
		(17 "Dwgs.User" user "User.Drawings")
		(19 "Cmts.User" user "User.Comments")
		(21 "Eco1.User" user "User.Eco1")
		(23 "Eco2.User" user "User.Eco2")
		(25 "Edge.Cuts" user "Board Geometry/Outline")
		(27 "Margin" user)
		(31 "F.CrtYd" user "Package Geometry/Place Bound Top")
		(29 "B.CrtYd" user "Package Geometry/Place Bound Bottom")
		(35 "F.Fab" user "Ref Des/Assembly Top")
		(33 "B.Fab" user "Ref Des/Assembly Bottom")
	)
	(footprint ""
		(layer "F.Cu")
		(at 451.866 -26.8478 90)
		(property "Reference" "C1W15"
			(at 0.97536 0.76708 0)
			(unlocked yes)
			(layer "F.SilkS")
			(effects
				(font
					(size 0.4064 0.254)
					(thickness 0.1524)
				)
			)
		)
		(property "Value" ""
			(at 0 0 90)
			(layer "F.Fab")
			(effects
				(font
					(size 1.27 1.27)
				)
			)
		)
		(duplicate_pad_numbers_are_jumpers no)
		(fp_poly
			(pts
				(xy -0.4953 -0.2032) (xy 0.4953 -0.2032) (xy 0.4953 1.6002) (xy -0.4953 1.6002)
			)
			(stroke
				(width 0)
				(type default)
			)
			(fill no)
			(layer "F.CrtYd")
		)
		(fp_line
			(start 0.4953 -0.2032)
			(end 0.4953 1.6002)
			(stroke
				(width 0.1)
				(type default)
			)
			(layer "F.Fab")
		)
		(fp_line
			(start -0.4953 -0.2032)
			(end 0.4953 -0.2032)
			(stroke
				(width 0.1)
				(type default)
			)
			(layer "F.Fab")
		)
		(fp_line
			(start 0.4953 1.6002)
			(end -0.4953 1.6002)
			(stroke
				(width 0.1)
				(type default)
			)
			(layer "F.Fab")
		)
		(fp_line
			(start -0.4953 1.6002)
			(end -0.4953 -0.2032)
			(stroke
				(width 0.1)
				(type default)
			)
			(layer "F.Fab")
		)
		(pad "1" smd rect
			(at 0 0 90)
			(size 0.762 0.889)
			(layers "F.Cu" "F.Mask" "F.Paste")
			(net "P2V5_AUX_BMC")
		)
		(pad "2" smd rect
			(at 0 1.397 90)
			(size 0.762 0.889)
			(layers "F.Cu" "F.Mask" "F.Paste")
			(net "GND")
		)
		(zone
			(layer "F.Cu")
			(hatch none 0.5)
			(connect_pads
				(clearance 0)
			)
			(min_thickness 0.25)
			(keepout
				(tracks not_allowed)
				(vias allowed)
				(pads allowed)
				(copperpour not_allowed)
				(footprints allowed)
			)
			(placement
				(enabled no)
				(sheetname "")
			)
			(fill
				(thermal_gap 0.5)
				(thermal_bridge_width 0.5)
				(island_removal_mode 0)
			)
			(polygon
				(pts
					(xy 452.3105 -26.4668) (xy 452.3105 -27.2288) (xy 452.8185 -27.2288) (xy 452.8185 -26.4668)
				)
			)
		)
	)
	(footprint ""
		(layer "F.Cu")
		(at 451.85838 -31.3055 90)
		(property "Reference" "R25W34"
			(at 0 0 90)
			(layer "F.SilkS")
			(hide yes)
			(effects
				(font
					(size 1.27 1.27)
				)
			)
		)
		(property "Value" "*"
			(at 0.064008 -4.108196 90)
			(unlocked yes)
			(layer "F.Fab")
			(hide yes)
			(effects
				(font
					(size 1.27 1.016)
					(thickness 0.1524)
				)
			)
		)
		(property "Device Type" "120R2F-GP_RCL_GP-120R2F-GP,64.A"
			(at 0.064008 -5.632196 90)
			(unlocked yes)
			(layer "F.Fab")
			(hide yes)
			(effects
				(font
					(size 1.27 1.016)
					(thickness 0.1524)
				)
			)
		)
		(duplicate_pad_numbers_are_jumpers no)
		(fp_line
			(start 0.508 -0.9398)
			(end -0.508 -0.9398)
			(stroke
				(width 0.1524)
				(type default)
			)
			(layer "F.SilkS")
		)
		(fp_line
			(start -0.508 -0.9398)
			(end -0.508 0.9398)
			(stroke
				(width 0.1524)
				(type default)
			)
			(layer "F.SilkS")
		)
		(fp_rect
			(start -0.508 0.9398)
			(end 0.508 -0.9398)
			(stroke
				(width 0)
				(type default)
			)
			(fill no)
			(layer "F.CrtYd")
		)
		(fp_rect
			(start -0.508 0.9398)
			(end 0.508 -0.9398)
			(stroke
				(width 0)
				(type default)
			)
			(fill no)
			(layer "F.Fab")
		)
		(pad "1" smd custom
			(at 0 -0.4445 90)
			(size 0.1397 0.1397)
			(layers "F.Cu" "F.Mask" "F.Paste")
			(net "BMC_M_WE_N")
			(options
				(clearance outline)
				(anchor circle)
			)
			(primitives
				(gr_poly
					(pts
						(arc
							(start -0.1778 -0.2794)
							(mid -0.249642 -0.249642)
							(end -0.2794 -0.1778)
						)
						(arc
							(start -0.2794 0.1778)
							(mid -0.249642 0.249642)
							(end -0.1778 0.2794)
						)
						(arc
							(start 0.1778 0.2794)
							(mid 0.249642 0.249642)
							(end 0.2794 0.1778)
						)
						(arc
							(start 0.2794 -0.1778)
							(mid 0.249642 -0.249642)
							(end 0.1778 -0.2794)
						)
					)
					(width 0)
					(fill yes)
				)
			)
		)
		(pad "2" smd custom
			(at 0 0.4445 90)
			(size 0.1397 0.1397)
			(layers "F.Cu" "F.Mask" "F.Paste")
			(net "P1V2_AUX_BMC")
			(options
				(clearance outline)
				(anchor circle)
			)
			(primitives
				(gr_poly
					(pts
						(arc
							(start -0.1778 -0.2794)
							(mid -0.249642 -0.249642)
							(end -0.2794 -0.1778)
						)
						(arc
							(start -0.2794 0.1778)
							(mid -0.249642 0.249642)
							(end -0.1778 0.2794)
						)
						(arc
							(start 0.1778 0.2794)
							(mid 0.249642 0.249642)
							(end 0.2794 0.1778)
						)
						(arc
							(start 0.2794 -0.1778)
							(mid 0.249642 -0.249642)
							(end 0.1778 -0.2794)
						)
					)
					(width 0)
					(fill yes)
				)
			)
		)
	)
	(footprint ""
		(layer "F.Cu")
		(at 248.8819 -140.208 -90)
		(property "Reference" "C5A12"
			(at 1.848866 0.752348 270)
			(unlocked yes)
			(layer "F.SilkS")
			(effects
				(font
					(size 1.27 0.9652)
					(thickness 0.1524)
				)
			)
		)
		(property "Value" ""
			(at 0 0 270)
			(layer "F.Fab")
			(effects
				(font
					(size 1.27 1.27)
				)
			)
		)
		(duplicate_pad_numbers_are_jumpers no)
		(fp_rect
			(start -0.500126 1.598422)
			(end 0.500126 -0.201422)
			(stroke
				(width 0)
				(type default)
			)
			(fill no)
			(layer "F.CrtYd")
		)
		(fp_line
			(start -0.500126 1.598422)
			(end -0.500126 -0.201422)
			(stroke
				(width 0.1)
				(type default)
			)
			(layer "F.Fab")
		)
		(fp_line
			(start 0.500126 1.598422)
			(end -0.500126 1.598422)
			(stroke
				(width 0.1)
				(type default)
			)
			(layer "F.Fab")
		)
		(fp_line
			(start -0.500126 -0.201422)
			(end 0.500126 -0.201422)
			(stroke
				(width 0.1)
				(type default)
			)
			(layer "F.Fab")
		)
		(fp_line
			(start 0.500126 -0.201422)
			(end 0.500126 1.598422)
			(stroke
				(width 0.1)
				(type default)
			)
			(layer "F.Fab")
		)
		(pad "1" smd rect
			(at 0 0 180)
			(size 0.889 0.9906)
			(layers "F.Cu" "F.Mask" "F.Paste")
			(net "PVDDQ_DEF")
		)
		(pad "2" smd rect
			(at 0 1.397 180)
			(size 0.889 0.9906)
			(layers "F.Cu" "F.Mask" "F.Paste")
			(net "GND")
		)
		(zone
			(layer "F.Cu")
			(hatch none 0.5)
			(connect_pads
				(clearance 0)
			)
			(min_thickness 0.25)
			(keepout
				(tracks not_allowed)
				(vias allowed)
				(pads allowed)
				(copperpour not_allowed)
				(footprints allowed)
			)
			(placement
				(enabled no)
				(sheetname "")
			)
			(fill
				(thermal_gap 0.5)
				(thermal_bridge_width 0.5)
				(island_removal_mode 0)
			)
			(polygon
				(pts
					(xy 247.9294 -140.7033) (xy 247.9294 -139.7127) (xy 248.4374 -139.7127) (xy 248.4374 -140.7033)
				)
			)
		)
		(zone
			(layer "F.Cu")
			(hatch none 0.5)
			(connect_pads
				(clearance 0)
			)
			(min_thickness 0.25)
			(keepout
				(tracks allowed)
				(vias not_allowed)
				(pads allowed)
				(copperpour not_allowed)
				(footprints allowed)
			)
			(placement
				(enabled no)
				(sheetname "")
			)
			(fill
				(thermal_gap 0.5)
				(thermal_bridge_width 0.5)
				(island_removal_mode 0)
			)
			(polygon
				(pts
					(xy 247.9294 -140.7033) (xy 247.9294 -139.7127) (xy 248.4374 -139.7127) (xy 248.4374 -140.7033)
				)
			)
		)
	)
)
